(kicad_pcb
	(version 20260206)
	(generator "pcbnew")
	(generator_version "10.0")
	(general
		(thickness 1.6)
		(legacy_teardrops no)
	)
	(paper "A4")
	(title_block
		(title "04192023_DAF0TMB3IC0_F0TG_MB_C_brd_V02_OCP.brd")
		(comment 1 "Grand Teton / footprints 457-462 of 8354")
	)
	(layers
		(0 "F.Cu" signal "TOP")
		(4 "In1.Cu" signal "GND")
		(6 "In2.Cu" signal "IN1")
		(8 "In3.Cu" signal "GND1")
		(10 "In4.Cu" signal "IN2")
		(12 "In5.Cu" signal "GND2")
		(14 "In6.Cu" signal "IN3")
		(16 "In7.Cu" signal "GND3")
		(18 "In8.Cu" signal "VCC")
		(20 "In9.Cu" signal "VCC1")
		(22 "In10.Cu" signal "GND4")
		(24 "In11.Cu" signal "IN4")
		(26 "In12.Cu" signal "GND5")
		(28 "In13.Cu" signal "IN5")
		(30 "In14.Cu" signal "GND6")
		(32 "In15.Cu" signal "IN6")
		(34 "In16.Cu" signal "GND7")
		(2 "B.Cu" signal "BOTTOM")
		(9 "F.Adhes" user "F.Adhesive")
		(11 "B.Adhes" user "B.Adhesive")
		(13 "F.Paste" user "Package Geometry/Pastemask Top")
		(15 "B.Paste" user "Package Geometry/Pastemask Bottom")
		(5 "F.SilkS" user "Ref Des/Silkscreen Top")
		(7 "B.SilkS" user "Ref Des/Silkscreen Bottom")
		(1 "F.Mask" user "Board Geometry/Soldermask Top")
		(3 "B.Mask" user "Board Geometry/Soldermask Bottom")
		(17 "Dwgs.User" user "User.Drawings")
		(19 "Cmts.User" user "User.Comments")
		(21 "Eco1.User" user "User.Eco1")
		(23 "Eco2.User" user "User.Eco2")
		(25 "Edge.Cuts" user "Board Geometry/Outline")
		(27 "Margin" user)
		(31 "F.CrtYd" user "Package Geometry/Place Bound Top")
		(29 "B.CrtYd" user "Package Geometry/Place Bound Bottom")
		(35 "F.Fab" user "Ref Des/Assembly Top")
		(33 "B.Fab" user "Ref Des/Assembly Bottom")
	)
	(footprint ""
		(layer "F.Cu")
		(at 306.262532 -410.406596 90)
		(property "Reference" "C7033"
			(at 0 0 90)
			(layer "F.SilkS")
			(hide yes)
			(effects
				(font
					(size 1.27 1.27)
				)
			)
		)
		(property "Value" ""
			(at 0 0 90)
			(layer "F.Fab")
			(effects
				(font
					(size 1.27 1.27)
				)
			)
		)
		(duplicate_pad_numbers_are_jumpers no)
		(fp_line
			(start 1.524 -0.762)
			(end 1.524 0.762)
			(stroke
				(width 0.1524)
				(type default)
			)
			(layer "F.SilkS")
		)
		(fp_line
			(start -1.524 -0.762)
			(end 1.524 -0.762)
			(stroke
				(width 0.1524)
				(type default)
			)
			(layer "F.SilkS")
		)
		(fp_line
			(start 1.524 0.762)
			(end -1.524 0.762)
			(stroke
				(width 0.1524)
				(type default)
			)
			(layer "F.SilkS")
		)
		(fp_line
			(start -1.524 0.762)
			(end -1.524 -0.762)
			(stroke
				(width 0.1524)
				(type default)
			)
			(layer "F.SilkS")
		)
		(fp_line
			(start 1.1049 -0.724916)
			(end -1.1049 -0.724916)
			(stroke
				(width 0.1)
				(type default)
			)
			(layer "F.Fab")
		)
		(fp_line
			(start -1.1049 -0.724916)
			(end -1.1049 0.724916)
			(stroke
				(width 0.1)
				(type default)
			)
			(layer "F.Fab")
		)
		(fp_line
			(start 1.1049 0.724916)
			(end 1.1049 -0.724916)
			(stroke
				(width 0.1)
				(type default)
			)
			(layer "F.Fab")
		)
		(fp_line
			(start -1.1049 0.724916)
			(end 1.1049 0.724916)
			(stroke
				(width 0.1)
				(type default)
			)
			(layer "F.Fab")
		)
		(pad "1" smd rect
			(at -0.889 0 270)
			(size 1.016 1.27)
			(layers "F.Cu" "F.Mask" "F.Paste")
			(net "P0V9_CPU0_RT_2D")
		)
		(pad "2" smd rect
			(at 0.889 0 270)
			(size 1.016 1.27)
			(layers "F.Cu" "F.Mask" "F.Paste")
			(net "GND")
		)
	)
	(footprint ""
		(layer "F.Cu")
		(at 273.378676 -119.761 180)
		(property "Reference" "R1316"
			(at 0 0 180)
			(layer "F.SilkS")
			(hide yes)
			(effects
				(font
					(size 1.27 1.27)
				)
			)
		)
		(property "Value" ""
			(at 0 0 180)
			(layer "F.Fab")
			(effects
				(font
					(size 1.27 1.27)
				)
			)
		)
		(duplicate_pad_numbers_are_jumpers no)
		(fp_line
			(start 0.7874 0.4064)
			(end -0.7874 0.4064)
			(stroke
				(width 0.1524)
				(type default)
			)
			(layer "F.SilkS")
		)
		(fp_line
			(start 0.7874 -0.4064)
			(end 0.7874 0.4064)
			(stroke
				(width 0.1524)
				(type default)
			)
			(layer "F.SilkS")
		)
		(fp_line
			(start -0.7874 0.4064)
			(end -0.7874 -0.4064)
			(stroke
				(width 0.1524)
				(type default)
			)
			(layer "F.SilkS")
		)
		(fp_line
			(start -0.7874 -0.4064)
			(end 0.7874 -0.4064)
			(stroke
				(width 0.1524)
				(type default)
			)
			(layer "F.SilkS")
		)
		(fp_line
			(start 0.67945 0.3048)
			(end 0.120396 0.3048)
			(stroke
				(width 0.1)
				(type default)
			)
			(layer "F.Fab")
		)
		(fp_line
			(start 0.67945 -0.3048)
			(end 0.67945 0.3048)
			(stroke
				(width 0.1)
				(type default)
			)
			(layer "F.Fab")
		)
		(fp_line
			(start 0.12065 -0.2794)
			(end 0.12065 -0.3048)
			(stroke
				(width 0.1)
				(type default)
			)
			(layer "F.Fab")
		)
		(fp_line
			(start 0.12065 -0.3048)
			(end 0.67945 -0.3048)
			(stroke
				(width 0.1)
				(type default)
			)
			(layer "F.Fab")
		)
		(fp_line
			(start 0.120396 0.3048)
			(end 0.120396 0.2794)
			(stroke
				(width 0.1)
				(type default)
			)
			(layer "F.Fab")
		)
		(fp_line
			(start 0.120396 0.2794)
			(end -0.12065 0.2794)
			(stroke
				(width 0.1)
				(type default)
			)
			(layer "F.Fab")
		)
		(fp_line
			(start -0.12065 0.3048)
			(end -0.67945 0.3048)
			(stroke
				(width 0.1)
				(type default)
			)
			(layer "F.Fab")
		)
		(fp_line
			(start -0.12065 0.2794)
			(end -0.12065 0.3048)
			(stroke
				(width 0.1)
				(type default)
			)
			(layer "F.Fab")
		)
		(fp_line
			(start -0.12065 -0.2794)
			(end 0.12065 -0.2794)
			(stroke
				(width 0.1)
				(type default)
			)
			(layer "F.Fab")
		)
		(fp_line
			(start -0.12065 -0.305054)
			(end -0.12065 -0.2794)
			(stroke
				(width 0.1)
				(type default)
			)
			(layer "F.Fab")
		)
		(fp_line
			(start -0.67945 0.3048)
			(end -0.67945 -0.305054)
			(stroke
				(width 0.1)
				(type default)
			)
			(layer "F.Fab")
		)
		(fp_line
			(start -0.67945 -0.305054)
			(end -0.12065 -0.305054)
			(stroke
				(width 0.1)
				(type default)
			)
			(layer "F.Fab")
		)
		(pad "1" smd circle
			(at -0.40005 0 180)
			(size 0 0)
			(layers "F.Cu" "F.Mask" "F.Paste")
			(net "P3V3_AUX")
		)
		(pad "2" smd circle
			(at 0.40005 0 180)
			(size 0 0)
			(layers "F.Cu" "F.Mask" "F.Paste")
			(net "SMB_ADC_SCL_R")
		)
	)
	(footprint ""
		(layer "F.Cu")
		(at 517.258808 -147.972526 -90)
		(property "Reference" "X2"
			(at -1.903222 3.256788 0)
			(unlocked yes)
			(layer "F.SilkS")
			(effects
				(font
					(size 0.7874 0.5842)
					(thickness 0.1524)
				)
				(justify left)
			)
		)
		(property "Value" ""
			(at 0 0 270)
			(layer "F.Fab")
			(effects
				(font
					(size 1.27 1.27)
				)
			)
		)
		(property "Device Type" "TP_TDR_4P_FTS_TH-TP_TDR_4P_DIP,EMPTY,TP15"
			(at 1.30175 1.27 0)
			(unlocked yes)
			(layer "F.Fab")
			(hide yes)
			(effects
				(font
					(size 0.635 0.4064)
					(thickness 0.1524)
				)
			)
		)
		(property "User Part Number" "N_A"
			(at 1.30175 1.27 0)
			(unlocked yes)
			(layer "Cmts.User")
			(hide yes)
			(effects
				(font
					(size 0.635 0.4064)
					(thickness 0.1524)
				)
			)
		)
		(duplicate_pad_numbers_are_jumpers no)
		(fp_line
			(start 0 3.81)
			(end 2.54 3.81)
			(stroke
				(width 0.1524)
				(type default)
			)
			(layer "F.SilkS")
		)
		(fp_line
			(start 2.54 3.81)
			(end 2.54 3.6703)
			(stroke
				(width 0.1524)
				(type default)
			)
			(layer "F.SilkS")
		)
		(fp_line
			(start 0 3.175)
			(end 0 3.81)
			(stroke
				(width 0.1524)
				(type default)
			)
			(layer "F.SilkS")
		)
		(fp_line
			(start 2.54 1.4097)
			(end 2.54 1.1303)
			(stroke
				(width 0.1524)
				(type default)
			)
			(layer "F.SilkS")
		)
		(fp_line
			(start 0 0.635)
			(end 0 1.905)
			(stroke
				(width 0.1524)
				(type default)
			)
			(layer "F.SilkS")
		)
		(fp_line
			(start 2.54 -1.1303)
			(end 2.54 -1.27)
			(stroke
				(width 0.1524)
				(type default)
			)
			(layer "F.SilkS")
		)
		(fp_line
			(start 0 -1.27)
			(end 0 -0.635)
			(stroke
				(width 0.1524)
				(type default)
			)
			(layer "F.SilkS")
		)
		(fp_line
			(start 2.54 -1.27)
			(end 0 -1.27)
			(stroke
				(width 0.1524)
				(type default)
			)
			(layer "F.SilkS")
		)
		(fp_poly
			(pts
				(xy -0.761746 0) (xy -2.285746 0.762) (xy -2.285746 -0.762)
			)
			(stroke
				(width 0)
				(type default)
			)
			(fill yes)
			(layer "F.SilkS")
		)
		(fp_line
			(start 0 3.81)
			(end 2.54 3.81)
			(stroke
				(width 0.1)
				(type default)
			)
			(layer "F.Fab")
		)
		(fp_line
			(start 2.54 3.81)
			(end 2.54 -1.27)
			(stroke
				(width 0.1)
				(type default)
			)
			(layer "F.Fab")
		)
		(fp_line
			(start 0 -1.27)
			(end 0 3.81)
			(stroke
				(width 0.1)
				(type default)
			)
			(layer "F.Fab")
		)
		(fp_line
			(start 2.54 -1.27)
			(end 0 -1.27)
			(stroke
				(width 0.1)
				(type default)
			)
			(layer "F.Fab")
		)
		(fp_poly
			(pts
				(xy -0.761746 0) (xy -2.285746 -0.762) (xy -2.285746 0.762)
			)
			(stroke
				(width 0)
				(type default)
			)
			(fill yes)
			(layer "F.Fab")
		)
		(pad "1" thru_hole circle
			(at 0 0 270)
			(size 1.0033 1.0033)
			(drill 0.249936)
			(layers "*.Cu" "*.Mask")
			(remove_unused_layers no)
			(net "TDR_DIFF_80_IN1_DP")
			(clearance 0.10795)
			(thermal_gap 0.10795)
			(padstack
				(mode front_inner_back)
				(layer "Inner"
					(shape circle)
					(size 0.8001 0.8001)
					(clearance 0.1524)
				)
				(layer "B.Cu"
					(shape circle)
					(size 1.0033 1.0033)
					(clearance 0.10795)
				)
			)
		)
		(pad "2" thru_hole circle
			(at 2.54 0 270)
			(size 1.9939 1.9939)
			(drill 0.249936)
			(layers "*.Cu" "*.Mask")
			(remove_unused_layers no)
			(net "T1_GND")
			(clearance 0.10795)
			(thermal_gap 0.10795)
			(padstack
				(mode front_inner_back)
				(layer "Inner"
					(shape circle)
					(size 0.8001 0.8001)
					(clearance 0.1524)
				)
				(layer "B.Cu"
					(shape circle)
					(size 1.9939 1.9939)
					(clearance 0.10795)
				)
			)
		)
		(pad "3" thru_hole circle
			(at 2.54 2.54 270)
			(size 1.9939 1.9939)
			(drill 0.249936)
			(layers "*.Cu" "*.Mask")
			(remove_unused_layers no)
			(net "T1_GND")
			(clearance 0.10795)
			(thermal_gap 0.10795)
			(padstack
				(mode front_inner_back)
				(layer "Inner"
					(shape circle)
					(size 0.8001 0.8001)
					(clearance 0.1524)
				)
				(layer "B.Cu"
					(shape circle)
					(size 1.9939 1.9939)
					(clearance 0.10795)
				)
			)
		)
		(pad "4" thru_hole circle
			(at 0 2.54 270)
			(size 1.0033 1.0033)
			(drill 0.249936)
			(layers "*.Cu" "*.Mask")
			(remove_unused_layers no)
			(net "TDR_DIFF_80_IN1_DN")
			(clearance 0.10795)
			(thermal_gap 0.10795)
			(padstack
				(mode front_inner_back)
				(layer "Inner"
					(shape circle)
					(size 0.8001 0.8001)
					(clearance 0.1524)
				)
				(layer "B.Cu"
					(shape circle)
					(size 1.0033 1.0033)
					(clearance 0.10795)
				)
			)
		)
	)
	(footprint ""
		(layer "F.Cu")
		(at 410.936186 -133.594348)
		(property "Reference" "PL8064"
			(at 0 0 0)
			(layer "F.SilkS")
			(hide yes)
			(effects
				(font
					(size 1.27 1.27)
				)
			)
		)
		(property "Value" ""
			(at 0 0 0)
			(layer "F.Fab")
			(effects
				(font
					(size 1.27 1.27)
				)
			)
		)
		(duplicate_pad_numbers_are_jumpers no)
		(fp_line
			(start -1.27 -0.5842)
			(end 1.27 -0.5842)
			(stroke
				(width 0.1524)
				(type default)
			)
			(layer "F.SilkS")
		)
		(fp_line
			(start -1.27 -0.5588)
			(end -1.27 -0.5842)
			(stroke
				(width 0.1524)
				(type default)
			)
			(layer "F.SilkS")
		)
		(fp_line
			(start -1.27 0.5842)
			(end -1.27 -0.5842)
			(stroke
				(width 0.1524)
				(type default)
			)
			(layer "F.SilkS")
		)
		(fp_line
			(start 1.27 0.5842)
			(end -1.27 0.5842)
			(stroke
				(width 0.1524)
				(type default)
			)
			(layer "F.SilkS")
		)
		(fp_line
			(start 1.27 0.5842)
			(end 1.27 -0.5842)
			(stroke
				(width 0.1524)
				(type default)
			)
			(layer "F.SilkS")
		)
		(fp_line
			(start -1.194308 -0.406654)
			(end -0.9144 -0.406654)
			(stroke
				(width 0.1)
				(type default)
			)
			(layer "F.Fab")
		)
		(fp_line
			(start -1.194308 0.406654)
			(end -1.194308 -0.406654)
			(stroke
				(width 0.1)
				(type default)
			)
			(layer "F.Fab")
		)
		(fp_line
			(start -0.9144 -0.508)
			(end 0.9144 -0.508)
			(stroke
				(width 0.1)
				(type default)
			)
			(layer "F.Fab")
		)
		(fp_line
			(start -0.9144 -0.406654)
			(end -0.9144 -0.508)
			(stroke
				(width 0.1)
				(type default)
			)
			(layer "F.Fab")
		)
		(fp_line
			(start -0.9144 0.406654)
			(end -1.194308 0.406654)
			(stroke
				(width 0.1)
				(type default)
			)
			(layer "F.Fab")
		)
		(fp_line
			(start -0.9144 0.508)
			(end -0.9144 0.406654)
			(stroke
				(width 0.1)
				(type default)
			)
			(layer "F.Fab")
		)
		(fp_line
			(start 0.9144 -0.508)
			(end 0.9144 -0.406654)
			(stroke
				(width 0.1)
				(type default)
			)
			(layer "F.Fab")
		)
		(fp_line
			(start 0.9144 -0.406654)
			(end 1.1938 -0.406654)
			(stroke
				(width 0.1)
				(type default)
			)
			(layer "F.Fab")
		)
		(fp_line
			(start 0.9144 0.4064)
			(end 0.9144 0.508)
			(stroke
				(width 0.1)
				(type default)
			)
			(layer "F.Fab")
		)
		(fp_line
			(start 0.9144 0.508)
			(end -0.9144 0.508)
			(stroke
				(width 0.1)
				(type default)
			)
			(layer "F.Fab")
		)
		(fp_line
			(start 1.1938 -0.406654)
			(end 1.1938 0.4064)
			(stroke
				(width 0.1)
				(type default)
			)
			(layer "F.Fab")
		)
		(fp_line
			(start 1.1938 0.4064)
			(end 0.9144 0.4064)
			(stroke
				(width 0.1)
				(type default)
			)
			(layer "F.Fab")
		)
		(pad "1" smd rect
			(at -0.7366 0 270)
			(size 0.7112 0.8128)
			(layers "F.Cu" "F.Mask" "F.Paste")
			(net "P12V_AUX")
		)
		(pad "2" smd rect
			(at 0.7366 0 270)
			(size 0.7112 0.8128)
			(layers "F.Cu" "F.Mask" "F.Paste")
			(net "SW_P5V_AUX_FLT")
		)
	)
	(footprint ""
		(layer "F.Cu")
		(at 239.152684 -52.01285)
		(property "Reference" "C1995"
			(at 0 0 0)
			(layer "F.SilkS")
			(hide yes)
			(effects
				(font
					(size 1.27 1.27)
				)
			)
		)
		(property "Value" ""
			(at 0 0 0)
			(layer "F.Fab")
			(effects
				(font
					(size 1.27 1.27)
				)
			)
		)
		(duplicate_pad_numbers_are_jumpers no)
		(fp_line
			(start -0.299974 -0.150114)
			(end 0.299974 -0.150114)
			(stroke
				(width 0.1)
				(type default)
			)
			(layer "F.Fab")
		)
		(fp_line
			(start -0.299974 0.150114)
			(end -0.299974 -0.150114)
			(stroke
				(width 0.1)
				(type default)
			)
			(layer "F.Fab")
		)
		(fp_line
			(start 0.299974 -0.150114)
			(end 0.299974 0.150114)
			(stroke
				(width 0.1)
				(type default)
			)
			(layer "F.Fab")
		)
		(fp_line
			(start 0.299974 0.150114)
			(end -0.299974 0.150114)
			(stroke
				(width 0.1)
				(type default)
			)
			(layer "F.Fab")
		)
		(pad "1" smd rect
			(at -0.2667 0)
			(size 0.3048 0.381)
			(layers "F.Cu" "F.Mask" "F.Paste")
			(net "P3E_CPU0_P4_TX_C_DP<0>")
		)
		(pad "2" smd rect
			(at 0.2667 0)
			(size 0.3048 0.381)
			(layers "F.Cu" "F.Mask" "F.Paste")
			(net "P3E_CPU0_P4_TX_DP<0>")
		)
	)
	(footprint ""
		(layer "F.Cu")
		(at 75.546458 -20.950682 180)
		(property "Reference" "PR3821"
			(at 0 0 180)
			(layer "F.SilkS")
			(hide yes)
			(effects
				(font
					(size 1.27 1.27)
				)
			)
		)
		(property "Value" ""
			(at 0 0 180)
			(layer "F.Fab")
			(effects
				(font
					(size 1.27 1.27)
				)
			)
		)
		(duplicate_pad_numbers_are_jumpers no)
		(fp_line
			(start 0.7874 0.4064)
			(end -0.7874 0.4064)
			(stroke
				(width 0.1524)
				(type default)
			)
			(layer "F.SilkS")
		)
		(fp_line
			(start 0.7874 -0.4064)
			(end 0.7874 0.4064)
			(stroke
				(width 0.1524)
				(type default)
			)
			(layer "F.SilkS")
		)
		(fp_line
			(start -0.7874 0.4064)
			(end -0.7874 -0.4064)
			(stroke
				(width 0.1524)
				(type default)
			)
			(layer "F.SilkS")
		)
		(fp_line
			(start -0.7874 -0.4064)
			(end 0.7874 -0.4064)
			(stroke
				(width 0.1524)
				(type default)
			)
			(layer "F.SilkS")
		)
		(fp_line
			(start 0.67945 0.3048)
			(end 0.120396 0.3048)
			(stroke
				(width 0.1)
				(type default)
			)
			(layer "F.Fab")
		)
		(fp_line
			(start 0.67945 -0.3048)
			(end 0.67945 0.3048)
			(stroke
				(width 0.1)
				(type default)
			)
			(layer "F.Fab")
		)
		(fp_line
			(start 0.12065 -0.2794)
			(end 0.12065 -0.3048)
			(stroke
				(width 0.1)
				(type default)
			)
			(layer "F.Fab")
		)
		(fp_line
			(start 0.12065 -0.3048)
			(end 0.67945 -0.3048)
			(stroke
				(width 0.1)
				(type default)
			)
			(layer "F.Fab")
		)
		(fp_line
			(start 0.120396 0.3048)
			(end 0.120396 0.2794)
			(stroke
				(width 0.1)
				(type default)
			)
			(layer "F.Fab")
		)
		(fp_line
			(start 0.120396 0.2794)
			(end -0.12065 0.2794)
			(stroke
				(width 0.1)
				(type default)
			)
			(layer "F.Fab")
		)
		(fp_line
			(start -0.12065 0.3048)
			(end -0.67945 0.3048)
			(stroke
				(width 0.1)
				(type default)
			)
			(layer "F.Fab")
		)
		(fp_line
			(start -0.12065 0.2794)
			(end -0.12065 0.3048)
			(stroke
				(width 0.1)
				(type default)
			)
			(layer "F.Fab")
		)
		(fp_line
			(start -0.12065 -0.2794)
			(end 0.12065 -0.2794)
			(stroke
				(width 0.1)
				(type default)
			)
			(layer "F.Fab")
		)
		(fp_line
			(start -0.12065 -0.305054)
			(end -0.12065 -0.2794)
			(stroke
				(width 0.1)
				(type default)
			)
			(layer "F.Fab")
		)
		(fp_line
			(start -0.67945 0.3048)
			(end -0.67945 -0.305054)
			(stroke
				(width 0.1)
				(type default)
			)
			(layer "F.Fab")
		)
		(fp_line
			(start -0.67945 -0.305054)
			(end -0.12065 -0.305054)
			(stroke
				(width 0.1)
				(type default)
			)
			(layer "F.Fab")
		)
		(pad "1" smd circle
			(at -0.40005 0 180)
			(size 0 0)
			(layers "F.Cu" "F.Mask" "F.Paste")
			(net "P12V_OCP_CB_2")
		)
		(pad "2" smd circle
			(at 0.40005 0 180)
			(size 0 0)
			(layers "F.Cu" "F.Mask" "F.Paste")
			(net "GND")
		)
	)
)
